# TIMECARD (Time Appliance Project (Time Card)) — schematic netlist excerpt (pin names and nets, part order shuffled) for the footprints in the layout excerpt that follows; sources: Cadence DE-HDL packaged netlist, KiCad conversion of R4006-B0001-02_R01.brd

C184  CAPACITOR  0.1UF 25V 10%  pkg SMC_0402R_H022  page 30 : \1\ = XP1R2V_EN_R ; \2\ = SG
R389  RESISTOR  33OHM 1%  pkg SMC_0402R_H016  page 26 : \1\ = SMA2_LED_GREEN_N ; \2\ = UNNAMED_14_LED4PV14_I266_4

(kicad_pcb
	(version 20260206)
	(generator "pcbnew")
	(generator_version "10.0")
	(general
		(thickness 1.6)
		(legacy_teardrops no)
	)
	(paper "A4")
	(title_block
		(title "timecard-production-celestica-r4006 — R4006-B0001-02_R01.brd")
		(comment 1 "Time Appliance Project (Time Card) / footprints 59-60 of 1113")
	)
	(layers
		(0 "F.Cu" signal "TOP")
		(4 "In1.Cu" signal "L02_GND1")
		(6 "In2.Cu" signal "L03_SIG1")
		(8 "In3.Cu" signal "L04_GND2")
		(10 "In4.Cu" signal "L05_VCC1")
		(12 "In5.Cu" signal "L06_VCC2")
		(14 "In6.Cu" signal "L07_GND3")
		(16 "In7.Cu" signal "L08_SIG2")
		(18 "In8.Cu" signal "L09_GND4")
		(2 "B.Cu" signal "BOTTOM")
		(9 "F.Adhes" user "F.Adhesive")
		(11 "B.Adhes" user "B.Adhesive")
		(13 "F.Paste" user "Package Geometry/Pastemask Top")
		(15 "B.Paste" user "Package Geometry/Pastemask Bottom")
		(5 "F.SilkS" user "Ref Des/Silkscreen Top")
		(7 "B.SilkS" user "Ref Des/Silkscreen Bottom")
		(1 "F.Mask" user "Board Geometry/Soldermask Top")
		(3 "B.Mask" user "Board Geometry/Soldermask Bottom")
		(17 "Dwgs.User" user "User.Drawings")
		(19 "Cmts.User" user "User.Comments")
		(21 "Eco1.User" user "User.Eco1")
		(23 "Eco2.User" user "User.Eco2")
		(25 "Edge.Cuts" user "Board Geometry/Outline")
		(27 "Margin" user)
		(31 "F.CrtYd" user "Package Geometry/Place Bound Top")
		(29 "B.CrtYd" user "Package Geometry/Place Bound Bottom")
		(35 "F.Fab" user "Ref Des/Assembly Top")
		(33 "B.Fab" user "Ref Des/Assembly Bottom")
	)
	(footprint ""
		(layer "F.Cu")
		(at 99.3648 -78.5368)
		(property "Reference" "C184"
			(at 2.78257 -1.4732 90)
			(unlocked yes)
			(layer "F.SilkS")
			(effects
				(font
					(size 0.7874 0.5842)
					(thickness 0.1524)
				)
			)
		)
		(property "Value" "VAL*"
			(at 0.0762 2.067306 0)
			(unlocked yes)
			(layer "F.Fab")
			(hide yes)
			(effects
				(font
					(size 0.7874 0.5842)
					(thickness 0.1524)
				)
			)
		)
		(property "Tolerance" "TOL*"
			(at 0.0762 3.032506 0)
			(unlocked yes)
			(layer "Cmts.User")
			(hide yes)
			(effects
				(font
					(size 0.7874 0.5842)
					(thickness 0.1524)
				)
			)
		)
		(property "User Part Number" "PARTNUM*"
			(at 0.1016 4.023106 0)
			(unlocked yes)
			(layer "Cmts.User")
			(hide yes)
			(effects
				(font
					(size 0.7874 0.5842)
					(thickness 0.1524)
				)
			)
		)
		(property "Device Type" "CAPACITOR-G105-0B104-EK,0.1UF,A"
			(at 0.0508 1.127506 0)
			(unlocked yes)
			(layer "F.Fab")
			(hide yes)
			(effects
				(font
					(size 0.7874 0.5842)
					(thickness 0.1524)
				)
			)
		)
		(duplicate_pad_numbers_are_jumpers no)
		(fp_line
			(start -1.143 -0.5588)
			(end -1.143 0.5588)
			(stroke
				(width 0.1)
				(type default)
			)
			(layer "F.SilkS")
		)
		(fp_line
			(start -1.143 0.5588)
			(end 1.143 0.5588)
			(stroke
				(width 0.1)
				(type default)
			)
			(layer "F.SilkS")
		)
		(fp_line
			(start 1.143 -0.5588)
			(end -1.143 -0.5588)
			(stroke
				(width 0.1)
				(type default)
			)
			(layer "F.SilkS")
		)
		(fp_line
			(start 1.143 0.5588)
			(end 1.143 -0.5588)
			(stroke
				(width 0.1)
				(type default)
			)
			(layer "F.SilkS")
		)
		(fp_rect
			(start -1.143 -0.5588)
			(end 1.143 0.5588)
			(stroke
				(width 0)
				(type default)
			)
			(fill no)
			(layer "F.CrtYd")
		)
		(fp_line
			(start -0.508 -0.3048)
			(end -0.508 0.3048)
			(stroke
				(width 0.1)
				(type default)
			)
			(layer "F.Fab")
		)
		(fp_line
			(start -0.508 0.3048)
			(end 0.508 0.3048)
			(stroke
				(width 0.1)
				(type default)
			)
			(layer "F.Fab")
		)
		(fp_line
			(start 0.508 -0.3048)
			(end -0.508 -0.3048)
			(stroke
				(width 0.1)
				(type default)
			)
			(layer "F.Fab")
		)
		(fp_line
			(start 0.508 0.3048)
			(end 0.508 -0.3048)
			(stroke
				(width 0.1)
				(type default)
			)
			(layer "F.Fab")
		)
		(pad "1" smd rect
			(at -0.5334 0)
			(size 0.7112 0.6096)
			(layers "F.Cu" "F.Mask" "F.Paste")
			(net "XP1R2V_EN_R")
		)
		(pad "2" smd rect
			(at 0.5334 0)
			(size 0.7112 0.6096)
			(layers "F.Cu" "F.Mask" "F.Paste")
			(net "SG")
		)
		(zone
			(layer "F.Cu")
			(hatch none 0.5)
			(connect_pads
				(clearance 0)
			)
			(min_thickness 0.25)
			(keepout
				(tracks allowed)
				(vias not_allowed)
				(pads allowed)
				(copperpour not_allowed)
				(footprints allowed)
			)
			(placement
				(enabled no)
				(sheetname "")
			)
			(fill
				(thermal_gap 0.5)
				(thermal_bridge_width 0.5)
				(island_removal_mode 0)
			)
			(polygon
				(pts
					(xy 99.2886 -78.8416) (xy 99.2886 -78.232) (xy 99.441 -78.232) (xy 99.441 -78.8416)
				)
			)
		)
	)
	(footprint ""
		(layer "F.Cu")
		(at 20.32 -33.02 180)
		(property "Reference" "R389"
			(at -2.667 -0.67437 0)
			(unlocked yes)
			(layer "F.SilkS")
			(effects
				(font
					(size 0.7874 0.5842)
					(thickness 0.1524)
				)
			)
		)
		(property "Value" "VAL*"
			(at 0.02032 2.13233 180)
			(unlocked yes)
			(layer "F.Fab")
			(hide yes)
			(effects
				(font
					(size 0.7874 0.5842)
					(thickness 0.1524)
				)
			)
		)
		(property "Tolerance" "TOL*"
			(at 0.044704 3.05435 180)
			(unlocked yes)
			(layer "Cmts.User")
			(hide yes)
			(effects
				(font
					(size 0.7874 0.5842)
					(thickness 0.1524)
				)
			)
		)
		(property "User Part Number" "PARTNUM*"
			(at 0.02032 4.024884 180)
			(unlocked yes)
			(layer "Cmts.User")
			(hide yes)
			(effects
				(font
					(size 0.7874 0.5842)
					(thickness 0.1524)
				)
			)
		)
		(property "Device Type" "RESISTOR-G155-133R0-01,33OHM,1%"
			(at 0.008382 1.210564 180)
			(unlocked yes)
			(layer "F.Fab")
			(hide yes)
			(effects
				(font
					(size 0.7874 0.5842)
					(thickness 0.1524)
				)
			)
		)
		(duplicate_pad_numbers_are_jumpers no)
		(fp_line
			(start 1.143 0.5588)
			(end 1.143 -0.5588)
			(stroke
				(width 0.1)
				(type default)
			)
			(layer "F.SilkS")
		)
		(fp_line
			(start 1.143 -0.5588)
			(end -1.143 -0.5588)
			(stroke
				(width 0.1)
				(type default)
			)
			(layer "F.SilkS")
		)
		(fp_line
			(start -1.143 0.5588)
			(end 1.143 0.5588)
			(stroke
				(width 0.1)
				(type default)
			)
			(layer "F.SilkS")
		)
		(fp_line
			(start -1.143 -0.5588)
			(end -1.143 0.5588)
			(stroke
				(width 0.1)
				(type default)
			)
			(layer "F.SilkS")
		)
		(fp_rect
			(start -1.143 -0.5588)
			(end 1.143 0.5588)
			(stroke
				(width 0)
				(type default)
			)
			(fill no)
			(layer "F.CrtYd")
		)
		(fp_line
			(start 0.508 0.3048)
			(end 0.508 -0.3048)
			(stroke
				(width 0.1)
				(type default)
			)
			(layer "F.Fab")
		)
		(fp_line
			(start 0.508 -0.3048)
			(end -0.508 -0.3048)
			(stroke
				(width 0.1)
				(type default)
			)
			(layer "F.Fab")
		)
		(fp_line
			(start -0.508 0.3048)
			(end 0.508 0.3048)
			(stroke
				(width 0.1)
				(type default)
			)
			(layer "F.Fab")
		)
		(fp_line
			(start -0.508 -0.3048)
			(end -0.508 0.3048)
			(stroke
				(width 0.1)
				(type default)
			)
			(layer "F.Fab")
		)
		(pad "1" smd rect
			(at -0.5334 0 180)
			(size 0.7112 0.6096)
			(layers "F.Cu" "F.Mask" "F.Paste")
			(net "SMA2_LED_GREEN_N")
		)
		(pad "2" smd rect
			(at 0.5334 0 180)
			(size 0.7112 0.6096)
			(layers "F.Cu" "F.Mask" "F.Paste")
			(net "UNNAMED_14_LED4PV14_I266_4")
		)
		(zone
			(layer "F.Cu")
			(hatch none 0.5)
			(connect_pads
				(clearance 0)
			)
			(min_thickness 0.25)
			(keepout
				(tracks not_allowed)
				(vias allowed)
				(pads allowed)
				(copperpour not_allowed)
				(footprints allowed)
			)
			(placement
				(enabled no)
				(sheetname "")
			)
			(fill
				(thermal_gap 0.5)
				(thermal_bridge_width 0.5)
				(island_removal_mode 0)
			)
			(polygon
				(pts
					(xy 20.3962 -32.7152) (xy 20.3962 -33.3248) (xy 20.2438 -33.3248) (xy 20.2438 -32.7152)
				)
			)
		)
		(zone
			(layer "F.Cu")
			(hatch none 0.5)
			(connect_pads
				(clearance 0)
			)
			(min_thickness 0.25)
			(keepout
				(tracks allowed)
				(vias not_allowed)
				(pads allowed)
				(copperpour not_allowed)
				(footprints allowed)
			)
			(placement
				(enabled no)
				(sheetname "")
			)
			(fill
				(thermal_gap 0.5)
				(thermal_bridge_width 0.5)
				(island_removal_mode 0)
			)
			(polygon
				(pts
					(xy 20.3962 -32.7152) (xy 20.3962 -33.3248) (xy 20.2438 -33.3248) (xy 20.2438 -32.7152)
				)
			)
		)
	)
)
